(kicad_pcb
	(version 20260206)
	(generator "pcbnew")
	(generator_version "10.0")
	(general
		(thickness 1.6)
		(legacy_teardrops no)
	)
	(paper "A4")
	(title_block
		(title "Bryce Canyon_R.DPB_16317-1_OCP.brd")
		(comment 1 "Bryce Canyon / footprints 1376-1381 of 2099")
	)
	(layers
		(0 "F.Cu" signal "TOP")
		(4 "In1.Cu" signal "L2GND")
		(6 "In2.Cu" signal "L3")
		(8 "In3.Cu" signal "L4VCC")
		(10 "In4.Cu" signal "L5VCC")
		(12 "In5.Cu" signal "L6")
		(14 "In6.Cu" signal "L7GND")
		(2 "B.Cu" signal "BOTTOM")
		(9 "F.Adhes" user "F.Adhesive")
		(11 "B.Adhes" user "B.Adhesive")
		(13 "F.Paste" user "Package Geometry/Pastemask Top")
		(15 "B.Paste" user "Package Geometry/Pastemask Bottom")
		(5 "F.SilkS" user "Ref Des/Silkscreen Top")
		(7 "B.SilkS" user "Ref Des/Silkscreen Bottom")
		(1 "F.Mask" user "Board Geometry/Soldermask Top")
		(3 "B.Mask" user "Board Geometry/Soldermask Bottom")
		(17 "Dwgs.User" user "User.Drawings")
		(19 "Cmts.User" user "User.Comments")
		(21 "Eco1.User" user "User.Eco1")
		(23 "Eco2.User" user "User.Eco2")
		(25 "Edge.Cuts" user "Board Geometry/Outline")
		(27 "Margin" user)
		(31 "F.CrtYd" user "Package Geometry/Place Bound Top")
		(29 "B.CrtYd" user "Package Geometry/Place Bound Bottom")
		(35 "F.Fab" user "Ref Des/Assembly Top")
		(33 "B.Fab" user "Ref Des/Assembly Bottom")
	)
	(footprint ""
		(layer "F.Cu")
		(at 181.991 -275.463 180)
		(property "Reference" "C101"
			(at 0 0 180)
			(layer "F.SilkS")
			(hide yes)
			(effects
				(font
					(size 1.27 1.27)
				)
			)
		)
		(property "Value" "SC1U25V3KX-GP"
			(at 0 -2.8194 180)
			(unlocked yes)
			(layer "F.Fab")
			(hide yes)
			(effects
				(font
					(size 1.016 1.016)
					(thickness 0.1524)
				)
			)
		)
		(property "Device Type" "C603H36"
			(at 0 -4.3434 180)
			(unlocked yes)
			(layer "F.Fab")
			(hide yes)
			(effects
				(font
					(size 1.016 1.016)
					(thickness 0.1524)
				)
			)
		)
		(duplicate_pad_numbers_are_jumpers no)
		(fp_line
			(start 0.508 0)
			(end -0.508 0)
			(stroke
				(width 0.2032)
				(type default)
			)
			(layer "F.SilkS")
		)
		(fp_rect
			(start -0.5842 1.3335)
			(end 0.5842 -1.3335)
			(stroke
				(width 0)
				(type default)
			)
			(fill no)
			(layer "F.CrtYd")
		)
		(fp_rect
			(start -0.5842 1.3335)
			(end 0.5842 -1.3335)
			(stroke
				(width 0)
				(type default)
			)
			(fill no)
			(layer "F.Fab")
		)
		(pad "1" smd custom
			(at 0 -0.762 180)
			(size 0.2159 0.2159)
			(layers "F.Cu" "F.Mask" "F.Paste")
			(net "P12V_HDD5")
			(options
				(clearance outline)
				(anchor circle)
			)
			(primitives
				(gr_poly
					(pts
						(arc
							(start -0.3302 -0.4318)
							(mid -0.402042 -0.402042)
							(end -0.4318 -0.3302)
						)
						(arc
							(start -0.4318 0.3302)
							(mid -0.402042 0.402042)
							(end -0.3302 0.4318)
						)
						(arc
							(start 0.3302 0.4318)
							(mid 0.402042 0.402042)
							(end 0.4318 0.3302)
						)
						(arc
							(start 0.4318 -0.3302)
							(mid 0.402042 -0.402042)
							(end 0.3302 -0.4318)
						)
					)
					(width 0)
					(fill yes)
				)
			)
		)
		(pad "2" smd custom
			(at 0 0.762 180)
			(size 0.2159 0.2159)
			(layers "F.Cu" "F.Mask" "F.Paste")
			(net "GND")
			(options
				(clearance outline)
				(anchor circle)
			)
			(primitives
				(gr_poly
					(pts
						(arc
							(start -0.3302 -0.4318)
							(mid -0.402042 -0.402042)
							(end -0.4318 -0.3302)
						)
						(arc
							(start -0.4318 0.3302)
							(mid -0.402042 0.402042)
							(end -0.3302 0.4318)
						)
						(arc
							(start 0.3302 0.4318)
							(mid 0.402042 0.402042)
							(end 0.4318 0.3302)
						)
						(arc
							(start 0.4318 -0.3302)
							(mid 0.402042 -0.402042)
							(end 0.3302 -0.4318)
						)
					)
					(width 0)
					(fill yes)
				)
			)
		)
	)
	(footprint ""
		(layer "F.Cu")
		(at 464.566 -28.829 90)
		(property "Reference" "C481"
			(at 0 0 90)
			(layer "F.SilkS")
			(hide yes)
			(effects
				(font
					(size 1.27 1.27)
				)
			)
		)
		(property "Value" "SCD033U25V2KX-GP"
			(at 1.1811 -2.7051 90)
			(unlocked yes)
			(layer "F.Fab")
			(hide yes)
			(effects
				(font
					(size 1.016 1.016)
					(thickness 0.1524)
				)
			)
		)
		(property "Device Type" "C402H22"
			(at 1.1811 -4.2291 90)
			(unlocked yes)
			(layer "F.Fab")
			(hide yes)
			(effects
				(font
					(size 1.016 1.016)
					(thickness 0.1524)
				)
			)
		)
		(duplicate_pad_numbers_are_jumpers no)
		(fp_rect
			(start -0.4318 0.9525)
			(end 0.4318 -0.9525)
			(stroke
				(width 0)
				(type default)
			)
			(fill no)
			(layer "F.CrtYd")
		)
		(fp_rect
			(start -0.4318 0.9525)
			(end 0.4318 -0.9525)
			(stroke
				(width 0)
				(type default)
			)
			(fill no)
			(layer "F.Fab")
		)
		(pad "1" smd custom
			(at 0 -0.4445 90)
			(size 0.1524 0.1524)
			(layers "F.Cu" "F.Mask" "F.Paste")
			(net "P12V_B")
			(options
				(clearance outline)
				(anchor circle)
			)
			(primitives
				(gr_poly
					(pts
						(arc
							(start 0.3048 -0.2032)
							(mid 0.275042 -0.275042)
							(end 0.2032 -0.3048)
						)
						(arc
							(start -0.2032 -0.3048)
							(mid -0.275042 -0.275042)
							(end -0.3048 -0.2032)
						)
						(arc
							(start -0.3048 0.2032)
							(mid -0.275042 0.275042)
							(end -0.2032 0.3048)
						)
						(arc
							(start 0.2032 0.3048)
							(mid 0.275042 0.275042)
							(end 0.3048 0.2032)
						)
					)
					(width 0)
					(fill yes)
				)
			)
		)
		(pad "2" smd custom
			(at 0 0.4445 90)
			(size 0.1524 0.1524)
			(layers "F.Cu" "F.Mask" "F.Paste")
			(net "SW_HDD_N34")
			(options
				(clearance outline)
				(anchor circle)
			)
			(primitives
				(gr_poly
					(pts
						(arc
							(start 0.3048 -0.2032)
							(mid 0.275042 -0.275042)
							(end 0.2032 -0.3048)
						)
						(arc
							(start -0.2032 -0.3048)
							(mid -0.275042 -0.275042)
							(end -0.3048 -0.2032)
						)
						(arc
							(start -0.3048 0.2032)
							(mid -0.275042 0.275042)
							(end -0.2032 0.3048)
						)
						(arc
							(start 0.2032 0.3048)
							(mid 0.275042 0.275042)
							(end 0.3048 0.2032)
						)
					)
					(width 0)
					(fill yes)
				)
			)
		)
	)
	(footprint ""
		(layer "F.Cu")
		(at 457.708 -250.4948 -90)
		(property "Reference" "C168"
			(at 0 0 270)
			(layer "F.SilkS")
			(hide yes)
			(effects
				(font
					(size 1.27 1.27)
				)
			)
		)
		(property "Value" "SCD033U25V2KX-GP"
			(at 1.1811 -2.7051 270)
			(unlocked yes)
			(layer "F.Fab")
			(hide yes)
			(effects
				(font
					(size 1.016 1.016)
					(thickness 0.1524)
				)
			)
		)
		(property "Device Type" "C402H22"
			(at 1.1811 -4.2291 270)
			(unlocked yes)
			(layer "F.Fab")
			(hide yes)
			(effects
				(font
					(size 1.016 1.016)
					(thickness 0.1524)
				)
			)
		)
		(duplicate_pad_numbers_are_jumpers no)
		(fp_rect
			(start -0.4318 0.9525)
			(end 0.4318 -0.9525)
			(stroke
				(width 0)
				(type default)
			)
			(fill no)
			(layer "F.CrtYd")
		)
		(fp_rect
			(start -0.4318 0.9525)
			(end 0.4318 -0.9525)
			(stroke
				(width 0)
				(type default)
			)
			(fill no)
			(layer "F.Fab")
		)
		(pad "1" smd custom
			(at 0 -0.4445 270)
			(size 0.1524 0.1524)
			(layers "F.Cu" "F.Mask" "F.Paste")
			(net "SW_HDD_P10")
			(options
				(clearance outline)
				(anchor circle)
			)
			(primitives
				(gr_poly
					(pts
						(arc
							(start 0.3048 -0.2032)
							(mid 0.275042 -0.275042)
							(end 0.2032 -0.3048)
						)
						(arc
							(start -0.2032 -0.3048)
							(mid -0.275042 -0.275042)
							(end -0.3048 -0.2032)
						)
						(arc
							(start -0.3048 0.2032)
							(mid -0.275042 0.275042)
							(end -0.2032 0.3048)
						)
						(arc
							(start 0.2032 0.3048)
							(mid 0.275042 0.275042)
							(end 0.3048 0.2032)
						)
					)
					(width 0)
					(fill yes)
				)
			)
		)
		(pad "2" smd custom
			(at 0 0.4445 270)
			(size 0.1524 0.1524)
			(layers "F.Cu" "F.Mask" "F.Paste")
			(net "GND")
			(options
				(clearance outline)
				(anchor circle)
			)
			(primitives
				(gr_poly
					(pts
						(arc
							(start 0.3048 -0.2032)
							(mid 0.275042 -0.275042)
							(end 0.2032 -0.3048)
						)
						(arc
							(start -0.2032 -0.3048)
							(mid -0.275042 -0.275042)
							(end -0.3048 -0.2032)
						)
						(arc
							(start -0.3048 0.2032)
							(mid -0.275042 0.275042)
							(end -0.2032 0.3048)
						)
						(arc
							(start 0.2032 0.3048)
							(mid 0.275042 0.275042)
							(end 0.3048 0.2032)
						)
					)
					(width 0)
					(fill yes)
				)
			)
		)
	)
	(footprint ""
		(layer "F.Cu")
		(at 469.49995 -377.219972 180)
		(property "Reference" "FLED4"
			(at 0 0 180)
			(layer "F.SilkS")
			(hide yes)
			(effects
				(font
					(size 1.27 1.27)
				)
			)
		)
		(property "Value" "LED-BY-14-GP"
			(at -4.7752 -2.1844 180)
			(unlocked yes)
			(layer "F.Fab")
			(hide yes)
			(effects
				(font
					(size 1.016 1.016)
					(thickness 0.1524)
				)
			)
		)
		(property "Device Type" "LED-100-3PH206"
			(at -4.7752 -3.7084 180)
			(unlocked yes)
			(layer "F.Fab")
			(hide yes)
			(effects
				(font
					(size 1.016 1.016)
					(thickness 0.1524)
				)
			)
		)
		(duplicate_pad_numbers_are_jumpers no)
		(fp_line
			(start 3.7592 8.0264)
			(end -3.7592 8.0264)
			(stroke
				(width 0.1524)
				(type default)
			)
			(layer "F.SilkS")
		)
		(fp_line
			(start 3.7592 -1.524)
			(end 3.7592 8.0264)
			(stroke
				(width 0.1524)
				(type default)
			)
			(layer "F.SilkS")
		)
		(fp_line
			(start 1.87833 3.63474)
			(end 0.58293 2.33934)
			(stroke
				(width 0.1524)
				(type default)
			)
			(layer "F.SilkS")
		)
		(fp_line
			(start 1.87833 2.33934)
			(end 2.81813 2.33934)
			(stroke
				(width 0.1524)
				(type default)
			)
			(layer "F.SilkS")
		)
		(fp_line
			(start 1.87833 1.04394)
			(end 1.87833 3.63474)
			(stroke
				(width 0.1524)
				(type default)
			)
			(layer "F.SilkS")
		)
		(fp_line
			(start 0.58293 3.05054)
			(end 0.58293 1.42494)
			(stroke
				(width 0.1524)
				(type default)
			)
			(layer "F.SilkS")
		)
		(fp_line
			(start 0.58293 2.33934)
			(end 1.87833 1.04394)
			(stroke
				(width 0.1524)
				(type default)
			)
			(layer "F.SilkS")
		)
		(fp_line
			(start -0.45847 3.05054)
			(end -0.45847 1.42494)
			(stroke
				(width 0.1524)
				(type default)
			)
			(layer "F.SilkS")
		)
		(fp_line
			(start -0.45847 2.33934)
			(end 0.58293 2.33934)
			(stroke
				(width 0.1524)
				(type default)
			)
			(layer "F.SilkS")
		)
		(fp_line
			(start -0.45847 2.33934)
			(end -1.75387 1.04394)
			(stroke
				(width 0.1524)
				(type default)
			)
			(layer "F.SilkS")
		)
		(fp_line
			(start -1.75387 3.63474)
			(end -0.45847 2.33934)
			(stroke
				(width 0.1524)
				(type default)
			)
			(layer "F.SilkS")
		)
		(fp_line
			(start -1.75387 2.33934)
			(end -3.45567 2.33934)
			(stroke
				(width 0.1524)
				(type default)
			)
			(layer "F.SilkS")
		)
		(fp_line
			(start -1.75387 1.04394)
			(end -1.75387 3.63474)
			(stroke
				(width 0.1524)
				(type default)
			)
			(layer "F.SilkS")
		)
		(fp_line
			(start -3.7592 8.0264)
			(end -3.7592 -1.524)
			(stroke
				(width 0.1524)
				(type default)
			)
			(layer "F.SilkS")
		)
		(fp_line
			(start -3.7592 -1.524)
			(end 3.7592 -1.524)
			(stroke
				(width 0.1524)
				(type default)
			)
			(layer "F.SilkS")
		)
		(fp_circle
			(center 2.54 0)
			(end 1.5494 0)
			(stroke
				(width 0.3048)
				(type default)
			)
			(fill no)
			(layer "F.SilkS")
		)
		(fp_circle
			(center 0 0)
			(end -0.9906 0)
			(stroke
				(width 0.3048)
				(type default)
			)
			(fill no)
			(layer "F.SilkS")
		)
		(fp_circle
			(center -2.54 0)
			(end -3.5306 0)
			(stroke
				(width 0.3048)
				(type default)
			)
			(fill no)
			(layer "F.SilkS")
		)
		(fp_rect
			(start -3.5052 7.7724)
			(end 3.5052 -1.27)
			(stroke
				(width 0)
				(type default)
			)
			(fill no)
			(layer "F.CrtYd")
		)
		(fp_poly
			(pts
				(xy -4.0132 8.2804) (xy -4.0132 -1.778) (xy -3.5052 -1.778) (xy -3.5052 7.7724) (xy 3.5052 7.7724)
				(xy 3.5052 -1.27) (xy -3.50012 -1.27) (xy -3.50012 -1.778) (xy 4.0132 -1.778) (xy 4.0132 8.2804)
			)
			(stroke
				(width 0)
				(type default)
			)
			(fill no)
			(layer "F.CrtYd")
		)
		(fp_rect
			(start -4.0132 8.2804)
			(end 4.0132 -1.778)
			(stroke
				(width 0)
				(type default)
			)
			(fill no)
			(layer "F.Fab")
		)
		(pad "1" thru_hole circle
			(at -2.54 0 180)
			(size 1.27 1.27)
			(drill 0.889)
			(layers "*.Cu" "*.Mask")
			(remove_unused_layers no)
			(net "FAN_LED_BLUE3")
			(clearance 0.1651)
			(thermal_gap 0.1651)
		)
		(pad "2" thru_hole circle
			(at 0 0 180)
			(size 1.27 1.27)
			(drill 0.889)
			(layers "*.Cu" "*.Mask")
			(remove_unused_layers no)
			(net "GND")
			(clearance 0.1651)
			(thermal_gap 0.1651)
		)
		(pad "3" thru_hole circle
			(at 2.54 0 180)
			(size 1.27 1.27)
			(drill 0.889)
			(layers "*.Cu" "*.Mask")
			(remove_unused_layers no)
			(net "FAN_LED_YELLOW_3")
			(clearance 0.1651)
			(thermal_gap 0.1651)
		)
	)
	(footprint ""
		(layer "F.Cu")
		(at 363.601 -131.318 -90)
		(property "Reference" "Q89"
			(at 0 0 270)
			(layer "F.SilkS")
			(hide yes)
			(effects
				(font
					(size 1.27 1.27)
				)
			)
		)
		(property "Value" "2N7002KDW-GP"
			(at -2.3622 -8.2042 270)
			(unlocked yes)
			(layer "F.Fab")
			(hide yes)
			(effects
				(font
					(size 1.016 1.016)
					(thickness 0.1524)
				)
			)
		)
		(property "Device Type" "SOT-363H44"
			(at -2.3622 -10.1092 270)
			(unlocked yes)
			(layer "F.Fab")
			(hide yes)
			(effects
				(font
					(size 1.016 1.016)
					(thickness 0.1524)
				)
			)
		)
		(duplicate_pad_numbers_are_jumpers no)
		(fp_line
			(start -1.4478 1.7018)
			(end 1.4478 1.7018)
			(stroke
				(width 0.1524)
				(type default)
			)
			(layer "F.SilkS")
		)
		(fp_line
			(start 1.4478 1.7018)
			(end 1.4478 -1.7018)
			(stroke
				(width 0.1524)
				(type default)
			)
			(layer "F.SilkS")
		)
		(fp_line
			(start -1.27 1.524)
			(end -1.27 0.6604)
			(stroke
				(width 0.4826)
				(type default)
			)
			(layer "F.SilkS")
		)
		(fp_line
			(start -1.4478 -1.7018)
			(end -1.4478 1.7018)
			(stroke
				(width 0.1524)
				(type default)
			)
			(layer "F.SilkS")
		)
		(fp_line
			(start 1.4478 -1.7018)
			(end -1.4478 -1.7018)
			(stroke
				(width 0.1524)
				(type default)
			)
			(layer "F.SilkS")
		)
		(fp_poly
			(pts
				(xy -1.524 -1.778) (xy 1.524 -1.778) (xy 1.524 1.778) (xy -1.524 1.778)
			)
			(stroke
				(width 0)
				(type default)
			)
			(fill no)
			(layer "F.CrtYd")
		)
		(fp_poly
			(pts
				(xy -1.524 -1.778) (xy 1.524 -1.778) (xy 1.524 1.778) (xy -1.524 1.778)
			)
			(stroke
				(width 0)
				(type default)
			)
			(fill no)
			(layer "F.Fab")
		)
		(pad "1" smd rect
			(at -0.65024 0.9398 270)
			(size 0.4064 1.016)
			(layers "F.Cu" "F.Mask" "F.Paste")
			(net "GND")
		)
		(pad "2" smd rect
			(at 0 0.9398 270)
			(size 0.4064 1.016)
			(layers "F.Cu" "F.Mask" "F.Paste")
			(net "SW_PWR_R_HDD19")
		)
		(pad "3" smd rect
			(at 0.65024 0.9398 270)
			(size 0.4064 1.016)
			(layers "F.Cu" "F.Mask" "F.Paste")
			(net "SW_HDD_P19")
		)
		(pad "4" smd rect
			(at 0.65024 -0.9398 270)
			(size 0.4064 1.016)
			(layers "F.Cu" "F.Mask" "F.Paste")
			(net "GND")
		)
		(pad "5" smd rect
			(at 0 -0.9398 270)
			(size 0.4064 1.016)
			(layers "F.Cu" "F.Mask" "F.Paste")
			(net "SW_HDD_G19")
		)
		(pad "6" smd rect
			(at -0.65024 -0.9398 270)
			(size 0.4064 1.016)
			(layers "F.Cu" "F.Mask" "F.Paste")
			(net "SW_HDD_R19")
		)
	)
	(footprint ""
		(layer "F.Cu")
		(at 329.819 -45.339 180)
		(property "Reference" "C426"
			(at 0 0 180)
			(layer "F.SilkS")
			(hide yes)
			(effects
				(font
					(size 1.27 1.27)
				)
			)
		)
		(property "Value" "SC1U25V3KX-GP"
			(at 0 -2.8194 180)
			(unlocked yes)
			(layer "F.Fab")
			(hide yes)
			(effects
				(font
					(size 1.016 1.016)
					(thickness 0.1524)
				)
			)
		)
		(property "Device Type" "C603H36"
			(at 0 -4.3434 180)
			(unlocked yes)
			(layer "F.Fab")
			(hide yes)
			(effects
				(font
					(size 1.016 1.016)
					(thickness 0.1524)
				)
			)
		)
		(duplicate_pad_numbers_are_jumpers no)
		(fp_line
			(start 0.508 0)
			(end -0.508 0)
			(stroke
				(width 0.2032)
				(type default)
			)
			(layer "F.SilkS")
		)
		(fp_rect
			(start -0.5842 1.3335)
			(end 0.5842 -1.3335)
			(stroke
				(width 0)
				(type default)
			)
			(fill no)
			(layer "F.CrtYd")
		)
		(fp_rect
			(start -0.5842 1.3335)
			(end 0.5842 -1.3335)
			(stroke
				(width 0)
				(type default)
			)
			(fill no)
			(layer "F.Fab")
		)
		(pad "1" smd custom
			(at 0 -0.762 180)
			(size 0.2159 0.2159)
			(layers "F.Cu" "F.Mask" "F.Paste")
			(net "P12V_HDD30")
			(options
				(clearance outline)
				(anchor circle)
			)
			(primitives
				(gr_poly
					(pts
						(arc
							(start -0.3302 -0.4318)
							(mid -0.402042 -0.402042)
							(end -0.4318 -0.3302)
						)
						(arc
							(start -0.4318 0.3302)
							(mid -0.402042 0.402042)
							(end -0.3302 0.4318)
						)
						(arc
							(start 0.3302 0.4318)
							(mid 0.402042 0.402042)
							(end 0.4318 0.3302)
						)
						(arc
							(start 0.4318 -0.3302)
							(mid 0.402042 -0.402042)
							(end 0.3302 -0.4318)
						)
					)
					(width 0)
					(fill yes)
				)
			)
		)
		(pad "2" smd custom
			(at 0 0.762 180)
			(size 0.2159 0.2159)
			(layers "F.Cu" "F.Mask" "F.Paste")
			(net "GND")
			(options
				(clearance outline)
				(anchor circle)
			)
			(primitives
				(gr_poly
					(pts
						(arc
							(start -0.3302 -0.4318)
							(mid -0.402042 -0.402042)
							(end -0.4318 -0.3302)
						)
						(arc
							(start -0.4318 0.3302)
							(mid -0.402042 0.402042)
							(end -0.3302 0.4318)
						)
						(arc
							(start 0.3302 0.4318)
							(mid 0.402042 0.402042)
							(end 0.4318 0.3302)
						)
						(arc
							(start 0.4318 -0.3302)
							(mid 0.402042 -0.402042)
							(end 0.3302 -0.4318)
						)
					)
					(width 0)
					(fill yes)
				)
			)
		)
	)
)
